# BASEBOARD_FAB2 (Tioga Pass) — schematic netlist excerpt (pin names and nets, part order shuffled) for the footprints in the layout excerpt that follows; sources: Cadence DE-HDL packaged netlist, KiCad conversion of Wiwynn_Tioga_Pass_MB.brd

C1M23  CAP_A  0.1UF 16V 10% X7R  pkg 0402V  page 186 : A = P12V_STBY ; B = GND
R9E1  RES  10.0K 1% CHIP  pkg 0402  page 139 : A = P3V3_STBY ; B = PU_JTAG_SPRV_TDI
C9G1  CAP  470PF 50V 10% X7R  pkg 0402LF  page 141 : A = LED_LAN_2_N ; B = GND

(kicad_pcb
	(version 20260206)
	(generator "pcbnew")
	(generator_version "10.0")
	(general
		(thickness 1.6)
		(legacy_teardrops no)
	)
	(paper "A4")
	(title_block
		(title "Wiwynn_Tioga_Pass_MB.brd")
		(comment 1 "Tioga Pass / footprints 2703-2705 of 4770")
	)
	(layers
		(0 "F.Cu" signal "TOP")
		(4 "In1.Cu" signal "L2GND")
		(6 "In2.Cu" signal "L3")
		(8 "In3.Cu" signal "L4GND")
		(10 "In4.Cu" signal "L5")
		(12 "In5.Cu" signal "L6GND")
		(14 "In6.Cu" signal "L7VCC")
		(16 "In7.Cu" signal "L8VCC")
		(18 "In8.Cu" signal "L9GND")
		(20 "In9.Cu" signal "L10")
		(22 "In10.Cu" signal "L11GND")
		(24 "In11.Cu" signal "L12")
		(26 "In12.Cu" signal "L13GND")
		(2 "B.Cu" signal "BOTTOM")
		(9 "F.Adhes" user "F.Adhesive")
		(11 "B.Adhes" user "B.Adhesive")
		(13 "F.Paste" user "Package Geometry/Pastemask Top")
		(15 "B.Paste" user "Package Geometry/Pastemask Bottom")
		(5 "F.SilkS" user "Ref Des/Silkscreen Top")
		(7 "B.SilkS" user "Ref Des/Silkscreen Bottom")
		(1 "F.Mask" user "Board Geometry/Soldermask Top")
		(3 "B.Mask" user "Board Geometry/Soldermask Bottom")
		(17 "Dwgs.User" user "User.Drawings")
		(19 "Cmts.User" user "User.Comments")
		(21 "Eco1.User" user "User.Eco1")
		(23 "Eco2.User" user "User.Eco2")
		(25 "Edge.Cuts" user "Board Geometry/Outline")
		(27 "Margin" user)
		(31 "F.CrtYd" user "Package Geometry/Place Bound Top")
		(29 "B.CrtYd" user "Package Geometry/Place Bound Bottom")
		(35 "F.Fab" user "Ref Des/Assembly Top")
		(33 "B.Fab" user "Ref Des/Assembly Bottom")
	)
	(footprint ""
		(layer "B.Cu")
		(at 483.0445 -48.514 -90)
		(property "Reference" "R9E1"
			(at 0 0 90)
			(layer "B.SilkS")
			(hide yes)
			(effects
				(font
					(size 1.27 1.27)
				)
				(justify mirror)
			)
		)
		(property "Value" ""
			(at 0 0 90)
			(layer "B.Fab")
			(effects
				(font
					(size 1.27 1.27)
				)
				(justify mirror)
			)
		)
		(duplicate_pad_numbers_are_jumpers no)
		(fp_poly
			(pts
				(xy 0.2794 -0.1016) (xy -0.2794 -0.1016) (xy -0.2794 0.9906) (xy 0.2794 0.9906)
			)
			(stroke
				(width 0)
				(type default)
			)
			(fill no)
			(layer "B.CrtYd")
		)
		(fp_line
			(start -0.2794 0.9906)
			(end -0.2794 -0.1016)
			(stroke
				(width 0.1)
				(type default)
			)
			(layer "B.Fab")
		)
		(fp_line
			(start 0.2794 0.9906)
			(end -0.2794 0.9906)
			(stroke
				(width 0.1)
				(type default)
			)
			(layer "B.Fab")
		)
		(fp_line
			(start -0.2794 -0.1016)
			(end 0.2794 -0.1016)
			(stroke
				(width 0.1)
				(type default)
			)
			(layer "B.Fab")
		)
		(fp_line
			(start 0.2794 -0.1016)
			(end 0.2794 0.9906)
			(stroke
				(width 0.1)
				(type default)
			)
			(layer "B.Fab")
		)
		(pad "1" smd rect
			(at 0 0 90)
			(size 0.508 0.508)
			(layers "B.Cu" "B.Mask" "B.Paste")
			(net "P3V3_STBY")
		)
		(pad "2" smd rect
			(at 0 0.889 90)
			(size 0.508 0.508)
			(layers "B.Cu" "B.Mask" "B.Paste")
			(net "PU_JTAG_SPRV_TDI")
		)
		(zone
			(layer "B.Cu")
			(hatch none 0.5)
			(connect_pads
				(clearance 0)
			)
			(min_thickness 0.25)
			(keepout
				(tracks not_allowed)
				(vias allowed)
				(pads allowed)
				(copperpour not_allowed)
				(footprints allowed)
			)
			(placement
				(enabled no)
				(sheetname "")
			)
			(fill
				(thermal_gap 0.5)
				(thermal_bridge_width 0.5)
				(island_removal_mode 0)
			)
			(polygon
				(pts
					(xy 482.4095 -48.26) (xy 482.4095 -48.768) (xy 482.7905 -48.768) (xy 482.7905 -48.26)
				)
			)
		)
		(zone
			(layer "B.Cu")
			(hatch none 0.5)
			(connect_pads
				(clearance 0)
			)
			(min_thickness 0.25)
			(keepout
				(tracks allowed)
				(vias not_allowed)
				(pads allowed)
				(copperpour not_allowed)
				(footprints allowed)
			)
			(placement
				(enabled no)
				(sheetname "")
			)
			(fill
				(thermal_gap 0.5)
				(thermal_bridge_width 0.5)
				(island_removal_mode 0)
			)
			(polygon
				(pts
					(xy 482.7905 -48.26) (xy 482.7905 -48.768) (xy 482.4095 -48.768) (xy 482.4095 -48.26)
				)
			)
		)
	)
	(footprint ""
		(layer "B.Cu")
		(at 484.691944 -17.934178 -90)
		(property "Reference" "C9G1"
			(at 0 0 90)
			(layer "B.SilkS")
			(hide yes)
			(effects
				(font
					(size 1.27 1.27)
				)
				(justify mirror)
			)
		)
		(property "Value" ""
			(at 0 0 90)
			(layer "B.Fab")
			(effects
				(font
					(size 1.27 1.27)
				)
				(justify mirror)
			)
		)
		(duplicate_pad_numbers_are_jumpers no)
		(fp_poly
			(pts
				(xy -0.3048 -0.1016) (xy -0.3048 0.9906) (xy 0.3048 0.9906) (xy 0.3048 -0.1016)
			)
			(stroke
				(width 0)
				(type default)
			)
			(fill no)
			(layer "B.CrtYd")
		)
		(fp_line
			(start -0.3048 0.9906)
			(end -0.3048 -0.1016)
			(stroke
				(width 0.1)
				(type default)
			)
			(layer "B.Fab")
		)
		(fp_line
			(start 0.3048 0.9906)
			(end -0.3048 0.9906)
			(stroke
				(width 0.1)
				(type default)
			)
			(layer "B.Fab")
		)
		(fp_line
			(start -0.3048 -0.1016)
			(end 0.3048 -0.1016)
			(stroke
				(width 0.1)
				(type default)
			)
			(layer "B.Fab")
		)
		(fp_line
			(start 0.3048 -0.1016)
			(end 0.3048 0.9906)
			(stroke
				(width 0.1)
				(type default)
			)
			(layer "B.Fab")
		)
		(pad "1" smd rect
			(at 0 0 90)
			(size 0.508 0.508)
			(layers "B.Cu" "B.Mask" "B.Paste")
			(net "LED_LAN_2_N")
		)
		(pad "2" smd rect
			(at 0 0.889 90)
			(size 0.508 0.508)
			(layers "B.Cu" "B.Mask" "B.Paste")
			(net "GND")
		)
		(zone
			(layer "B.Cu")
			(hatch none 0.5)
			(connect_pads
				(clearance 0)
			)
			(min_thickness 0.25)
			(keepout
				(tracks not_allowed)
				(vias allowed)
				(pads allowed)
				(copperpour not_allowed)
				(footprints allowed)
			)
			(placement
				(enabled no)
				(sheetname "")
			)
			(fill
				(thermal_gap 0.5)
				(thermal_bridge_width 0.5)
				(island_removal_mode 0)
			)
			(polygon
				(pts
					(xy 484.056944 -17.680178) (xy 484.056944 -18.188178) (xy 484.437944 -18.188178) (xy 484.437944 -17.680178)
				)
			)
		)
		(zone
			(layer "B.Cu")
			(hatch none 0.5)
			(connect_pads
				(clearance 0)
			)
			(min_thickness 0.25)
			(keepout
				(tracks allowed)
				(vias not_allowed)
				(pads allowed)
				(copperpour not_allowed)
				(footprints allowed)
			)
			(placement
				(enabled no)
				(sheetname "")
			)
			(fill
				(thermal_gap 0.5)
				(thermal_bridge_width 0.5)
				(island_removal_mode 0)
			)
			(polygon
				(pts
					(xy 484.437944 -17.680178) (xy 484.437944 -18.188178) (xy 484.056944 -18.188178) (xy 484.056944 -17.680178)
				)
			)
		)
	)
	(footprint ""
		(layer "B.Cu")
		(at 486.156 -113.2332 -90)
		(property "Reference" "C1M23"
			(at 0 0 90)
			(layer "B.SilkS")
			(hide yes)
			(effects
				(font
					(size 1.27 1.27)
				)
				(justify mirror)
			)
		)
		(property "Value" ""
			(at 0 0 90)
			(layer "B.Fab")
			(effects
				(font
					(size 1.27 1.27)
				)
				(justify mirror)
			)
		)
		(duplicate_pad_numbers_are_jumpers no)
		(fp_rect
			(start 0.3048 0.9906)
			(end -0.3048 -0.1016)
			(stroke
				(width 0)
				(type default)
			)
			(fill no)
			(layer "B.CrtYd")
		)
		(fp_line
			(start -0.3048 0.9906)
			(end -0.3048 -0.1016)
			(stroke
				(width 0.1)
				(type default)
			)
			(layer "B.Fab")
		)
		(fp_line
			(start 0.3048 0.9906)
			(end -0.3048 0.9906)
			(stroke
				(width 0.1)
				(type default)
			)
			(layer "B.Fab")
		)
		(fp_line
			(start -0.3048 -0.1016)
			(end 0.3048 -0.1016)
			(stroke
				(width 0.1)
				(type default)
			)
			(layer "B.Fab")
		)
		(fp_line
			(start 0.3048 -0.1016)
			(end 0.3048 0.9906)
			(stroke
				(width 0.1)
				(type default)
			)
			(layer "B.Fab")
		)
		(pad "1" smd rect
			(at 0 0 90)
			(size 0.508 0.508)
			(layers "B.Cu" "B.Mask" "B.Paste")
			(net "P12V_STBY")
		)
		(pad "2" smd rect
			(at 0 0.889 90)
			(size 0.508 0.508)
			(layers "B.Cu" "B.Mask" "B.Paste")
			(net "GND")
		)
		(zone
			(layer "B.Cu")
			(hatch none 0.5)
			(connect_pads
				(clearance 0)
			)
			(min_thickness 0.25)
			(keepout
				(tracks allowed)
				(vias not_allowed)
				(pads allowed)
				(copperpour not_allowed)
				(footprints allowed)
			)
			(placement
				(enabled no)
				(sheetname "")
			)
			(fill
				(thermal_gap 0.5)
				(thermal_bridge_width 0.5)
				(island_removal_mode 0)
			)
			(polygon
				(pts
					(xy 485.521 -112.9792) (xy 485.902 -112.9792) (xy 485.902 -113.4872) (xy 485.521 -113.4872)
				)
			)
		)
		(zone
			(layer "B.Cu")
			(hatch none 0.5)
			(connect_pads
				(clearance 0)
			)
			(min_thickness 0.25)
			(keepout
				(tracks not_allowed)
				(vias allowed)
				(pads allowed)
				(copperpour not_allowed)
				(footprints allowed)
			)
			(placement
				(enabled no)
				(sheetname "")
			)
			(fill
				(thermal_gap 0.5)
				(thermal_bridge_width 0.5)
				(island_removal_mode 0)
			)
			(polygon
				(pts
					(xy 485.521 -112.9792) (xy 485.902 -112.9792) (xy 485.902 -113.4872) (xy 485.521 -113.4872)
				)
			)
		)
	)
)
